# S9S_MB_2U (Grand Teton) — schematic parts with pin connectivity, parts 1662–1664 of 6093; source: Cadence DE-HDL packaged netlist (pstxprt.dat, pstxnet.dat, pstchip.dat)

J106  CONN112_10137002101LF  CONN112_10137002-101LF IO  pkg HSD_F112D8_P2W1-2_RDH  page 137
  A1  A1  BI  = PRSNT_CABLE_SWB_B1_N
  A2  A2  BI  = GND
  A3  A3  BI  = FM_SWB_PWRGD
  A4  A4  BI  = GND
  A5  A5  BI  = NC_J106_A5
  A6  A6  BI  = GND
  A7  A7  BI  = PRSNT_CABLE_GPU_A1_N
  A8  A8  BI  = GND
  B1  B1  BI  = GND
  B2  B2  BI  = P5E_CPU0_PE3_RX_DP<14>
  B3  B3  BI  = GND
  B4  B4  BI  = P5E_CPU0_PE3_RX_DP<12>
  B5  B5  BI  = GND
  B6  B6  BI  = P5E_CPU0_PE3_RX_DN<10>
  B7  B7  BI  = GND
  B8  B8  BI  = P5E_CPU0_PE3_RX_DN<8>
  C1  C1  BI  = P5E_CPU0_PE3_RX_DP<15>
  C2  C2  BI  = P5E_CPU0_PE3_RX_DN<14>
  C3  C3  BI  = P5E_CPU0_PE3_RX_DP<13>
  C4  C4  BI  = P5E_CPU0_PE3_RX_DN<12>
  C5  C5  BI  = P5E_CPU0_PE3_RX_DN<11>
  C6  C6  BI  = P5E_CPU0_PE3_RX_DP<10>
  C7  C7  BI  = P5E_CPU0_PE3_RX_DN<9>
  C8  C8  BI  = P5E_CPU0_PE3_RX_DP<8>
  D1  D1  BI  = P5E_CPU0_PE3_RX_DN<15>
  D2  D2  BI  = GND
  D3  D3  BI  = P5E_CPU0_PE3_RX_DN<13>
  D4  D4  BI  = GND
  D5  D5  BI  = P5E_CPU0_PE3_RX_DP<11>
  D6  D6  BI  = GND
  D7  D7  BI  = P5E_CPU0_PE3_RX_DP<9>
  D8  D8  BI  = GND
  E1  E1  BI  = GND
  E2  E2  BI  = P5E_CPU0_PE2_RX_DP<14>
  E3  E3  BI  = GND
  E4  E4  BI  = P5E_CPU0_PE2_RX_DP<12>
  E5  E5  BI  = GND
  E6  E6  BI  = P5E_CPU0_PE2_RX_DP<10>
  E7  E7  BI  = GND
  E8  E8  BI  = P5E_CPU0_PE2_RX_DP<8>
  F1  F1  BI  = P5E_CPU0_PE2_RX_DP<15>
  F2  F2  BI  = P5E_CPU0_PE2_RX_DN<14>
  F3  F3  BI  = P5E_CPU0_PE2_RX_DP<13>
  F4  F4  BI  = P5E_CPU0_PE2_RX_DN<12>
  F5  F5  BI  = P5E_CPU0_PE2_RX_DP<11>
  F6  F6  BI  = P5E_CPU0_PE2_RX_DN<10>
  F7  F7  BI  = P5E_CPU0_PE2_RX_DP<9>
  F8  F8  BI  = P5E_CPU0_PE2_RX_DN<8>
  G1  G1  BI  = P5E_CPU0_PE2_RX_DN<15>
  G2  G2  BI  = GND
  G3  G3  BI  = P5E_CPU0_PE2_RX_DN<13>
  G4  G4  BI  = GND
  G5  G5  BI  = P5E_CPU0_PE2_RX_DN<11>
  G6  G6  BI  = GND
  G7  G7  BI  = P5E_CPU0_PE2_RX_DN<9>
  G8  G8  BI  = GND
  H1  H1  BI  = GND
  H2  H2  BI  = P5E_CPU0_PE3_TX_C_DN<14>
  H3  H3  BI  = GND
  H4  H4  BI  = P5E_CPU0_PE3_TX_C_DN<12>
  H5  H5  BI  = GND
  H6  H6  BI  = P5E_CPU0_PE3_TX_C_DN<10>
  H7  H7  BI  = GND
  H8  H8  BI  = P5E_CPU0_PE3_TX_C_DN<8>
  I1  I1  BI  = P5E_CPU0_PE3_TX_C_DN<15>
  I2  I2  BI  = P5E_CPU0_PE3_TX_C_DP<14>
  I3  I3  BI  = P5E_CPU0_PE3_TX_C_DN<13>
  I4  I4  BI  = P5E_CPU0_PE3_TX_C_DP<12>
  I5  I5  BI  = P5E_CPU0_PE3_TX_C_DN<11>
  I6  I6  BI  = P5E_CPU0_PE3_TX_C_DP<10>
  I7  I7  BI  = P5E_CPU0_PE3_TX_C_DN<9>
  I8  I8  BI  = P5E_CPU0_PE3_TX_C_DP<8>
  J1  J1  BI  = P5E_CPU0_PE3_TX_C_DP<15>
  J2  J2  BI  = GND
  J3  J3  BI  = P5E_CPU0_PE3_TX_C_DP<13>
  J4  J4  BI  = GND
  J5  J5  BI  = P5E_CPU0_PE3_TX_C_DP<11>
  J6  J6  BI  = GND
  J7  J7  BI  = P5E_CPU0_PE3_TX_C_DP<9>
  J8  J8  BI  = GND
  K1  K1  BI  = GND
  K2  K2  BI  = P5E_CPU0_PE2_TX_C_DP<14>
  K3  K3  BI  = GND
  K4  K4  BI  = P5E_CPU0_PE2_TX_C_DP<12>
  K5  K5  BI  = GND
  K6  K6  BI  = P5E_CPU0_PE2_TX_C_DP<10>
  K7  K7  BI  = GND
  K8  K8  BI  = P5E_CPU0_PE2_TX_C_DP<8>
  L1  L1  BI  = P5E_CPU0_PE2_TX_C_DN<15>
  L2  L2  BI  = P5E_CPU0_PE2_TX_C_DN<14>
  L3  L3  BI  = P5E_CPU0_PE2_TX_C_DP<13>
  L4  L4  BI  = P5E_CPU0_PE2_TX_C_DN<12>
  L5  L5  BI  = P5E_CPU0_PE2_TX_C_DP<11>
  L6  L6  BI  = P5E_CPU0_PE2_TX_C_DN<10>
  L7  L7  BI  = P5E_CPU0_PE2_TX_C_DP<9>
  L8  L8  BI  = P5E_CPU0_PE2_TX_C_DN<8>
  M1  M1  BI  = P5E_CPU0_PE2_TX_C_DP<15>
  M2  M2  BI  = GND
  M3  M3  BI  = P5E_CPU0_PE2_TX_C_DN<13>
  M4  M4  BI  = GND
  M5  M5  BI  = P5E_CPU0_PE2_TX_C_DN<11>
  M6  M6  BI  = GND
  M7  M7  BI  = P5E_CPU0_PE2_TX_C_DN<9>
  M8  M8  BI  = GND
  N1  N1  BI  = GND
  N2  N2  BI  = I3C_BMC_SWB_BUF_SDA
  N3  N3  BI  = GND
  N4  N4  BI  = I3C_BMC_SWB_BUF_SCL
  N5  N5  BI  = GND
  N6  N6  BI  = UART_BMC_BIC_RX
  N7  N7  BI  = GND
  N8  N8  BI  = UART_BMC_BIC_TX

J107  CONN112_10137002101LF  CONN112_10137002-101LF IO  pkg HSD_F112D8_P2W1-2_RDH  page 138
  A1  A1  BI  = NC_J107_A1
  A2  A2  BI  = GND
  A3  A3  BI  = NC_J107_A3
  A4  A4  BI  = GND
  A5  A5  BI  = NC_J107_A5
  A6  A6  BI  = GND
  A7  A7  BI  = SWB_HSC_PWRGD
  A8  A8  BI  = GND
  B1  B1  BI  = GND
  B2  B2  BI  = P5E_CPU0_PE0_RX_DN<6>
  B3  B3  BI  = GND
  B4  B4  BI  = P5E_CPU0_PE0_RX_DN<4>
  B5  B5  BI  = GND
  B6  B6  BI  = P5E_CPU0_PE0_RX_DN<2>
  B7  B7  BI  = GND
  B8  B8  BI  = P5E_CPU0_PE0_RX_DN<0>
  C1  C1  BI  = P5E_CPU0_PE0_RX_DN<7>
  C2  C2  BI  = P5E_CPU0_PE0_RX_DP<6>
  C3  C3  BI  = P5E_CPU0_PE0_RX_DN<5>
  C4  C4  BI  = P5E_CPU0_PE0_RX_DP<4>
  C5  C5  BI  = P5E_CPU0_PE0_RX_DP<3>
  C6  C6  BI  = P5E_CPU0_PE0_RX_DP<2>
  C7  C7  BI  = P5E_CPU0_PE0_RX_DP<1>
  C8  C8  BI  = P5E_CPU0_PE0_RX_DP<0>
  D1  D1  BI  = P5E_CPU0_PE0_RX_DP<7>
  D2  D2  BI  = GND
  D3  D3  BI  = P5E_CPU0_PE0_RX_DP<5>
  D4  D4  BI  = GND
  D5  D5  BI  = P5E_CPU0_PE0_RX_DN<3>
  D6  D6  BI  = GND
  D7  D7  BI  = P5E_CPU0_PE0_RX_DN<1>
  D8  D8  BI  = GND
  E1  E1  BI  = GND
  E2  E2  BI  = P5E_CPU0_PE4_RX_DP<9>
  E3  E3  BI  = GND
  E4  E4  BI  = P5E_CPU0_PE4_RX_DP<11>
  E5  E5  BI  = GND
  E6  E6  BI  = P5E_CPU0_PE4_RX_DP<13>
  E7  E7  BI  = GND
  E8  E8  BI  = P5E_CPU0_PE4_RX_DP<15>
  F1  F1  BI  = P5E_CPU0_PE4_RX_DN<8>
  F2  F2  BI  = P5E_CPU0_PE4_RX_DN<9>
  F3  F3  BI  = P5E_CPU0_PE4_RX_DN<10>
  F4  F4  BI  = P5E_CPU0_PE4_RX_DN<11>
  F5  F5  BI  = P5E_CPU0_PE4_RX_DN<12>
  F6  F6  BI  = P5E_CPU0_PE4_RX_DN<13>
  F7  F7  BI  = P5E_CPU0_PE4_RX_DN<14>
  F8  F8  BI  = P5E_CPU0_PE4_RX_DN<15>
  G1  G1  BI  = P5E_CPU0_PE4_RX_DP<8>
  G2  G2  BI  = GND
  G3  G3  BI  = P5E_CPU0_PE4_RX_DP<10>
  G4  G4  BI  = GND
  G5  G5  BI  = P5E_CPU0_PE4_RX_DP<12>
  G6  G6  BI  = GND
  G7  G7  BI  = P5E_CPU0_PE4_RX_DP<14>
  G8  G8  BI  = GND
  H1  H1  BI  = GND
  H2  H2  BI  = P5E_CPU0_PE0_TX_C_DN<6>
  H3  H3  BI  = GND
  H4  H4  BI  = P5E_CPU0_PE0_TX_C_DN<4>
  H5  H5  BI  = GND
  H6  H6  BI  = P5E_CPU0_PE0_TX_C_DN<2>
  H7  H7  BI  = GND
  H8  H8  BI  = P5E_CPU0_PE0_TX_C_DN<0>
  I1  I1  BI  = P5E_CPU0_PE0_TX_C_DN<7>
  I2  I2  BI  = P5E_CPU0_PE0_TX_C_DP<6>
  I3  I3  BI  = P5E_CPU0_PE0_TX_C_DN<5>
  I4  I4  BI  = P5E_CPU0_PE0_TX_C_DP<4>
  I5  I5  BI  = P5E_CPU0_PE0_TX_C_DN<3>
  I6  I6  BI  = P5E_CPU0_PE0_TX_C_DP<2>
  I7  I7  BI  = P5E_CPU0_PE0_TX_C_DN<1>
  I8  I8  BI  = P5E_CPU0_PE0_TX_C_DP<0>
  J1  J1  BI  = P5E_CPU0_PE0_TX_C_DP<7>
  J2  J2  BI  = GND
  J3  J3  BI  = P5E_CPU0_PE0_TX_C_DP<5>
  J4  J4  BI  = GND
  J5  J5  BI  = P5E_CPU0_PE0_TX_C_DP<3>
  J6  J6  BI  = GND
  J7  J7  BI  = P5E_CPU0_PE0_TX_C_DP<1>
  J8  J8  BI  = GND
  K1  K1  BI  = GND
  K2  K2  BI  = P5E_CPU0_PE4_TX_C_DN<9>
  K3  K3  BI  = GND
  K4  K4  BI  = P5E_CPU0_PE4_TX_C_DP<11>
  K5  K5  BI  = GND
  K6  K6  BI  = P5E_CPU0_PE4_TX_C_DN<13>
  K7  K7  BI  = GND
  K8  K8  BI  = P5E_CPU0_PE4_TX_C_DN<15>
  L1  L1  BI  = P5E_CPU0_PE4_TX_C_DN<8>
  L2  L2  BI  = P5E_CPU0_PE4_TX_C_DP<9>
  L3  L3  BI  = P5E_CPU0_PE4_TX_C_DN<10>
  L4  L4  BI  = P5E_CPU0_PE4_TX_C_DN<11>
  L5  L5  BI  = P5E_CPU0_PE4_TX_C_DN<12>
  L6  L6  BI  = P5E_CPU0_PE4_TX_C_DP<13>
  L7  L7  BI  = P5E_CPU0_PE4_TX_C_DN<14>
  L8  L8  BI  = P5E_CPU0_PE4_TX_C_DP<15>
  M1  M1  BI  = P5E_CPU0_PE4_TX_C_DP<8>
  M2  M2  BI  = GND
  M3  M3  BI  = P5E_CPU0_PE4_TX_C_DP<10>
  M4  M4  BI  = GND
  M5  M5  BI  = P5E_CPU0_PE4_TX_C_DP<12>
  M6  M6  BI  = GND
  M7  M7  BI  = P5E_CPU0_PE4_TX_C_DP<14>
  M8  M8  BI  = GND
  N1  N1  BI  = GND
  N2  N2  BI  = PRSNT_CABLE_SWB_B2_N
  N3  N3  BI  = GND
  N4  N4  BI  = NC_J107_N4
  N5  N5  BI  = GND
  N6  N6  BI  = NC_J107_N6
  N7  N7  BI  = GND
  N8  N8  BI  = SWB_HSC_EN_BUF

J108  CONN112_10137002101LF  CONN112_10137002-101LF IO  pkg HSD_F112D8_P2W1-2_RDH  page 139
  A1  A1  BI  = GPU_3V3IO_RSVD3_FFU
  A2  A2  BI  = GND
  A3  A3  BI  = PRSNT_CABLE_GPU_A2_N
  A4  A4  BI  = GND
  A5  A5  BI  = GPU_3V3IO_RSVD5_FFU
  A6  A6  BI  = GND
  A7  A7  BI  = GPU_FPGA_OVERT_N
  A8  A8  BI  = GND
  B1  B1  BI  = GND
  B2  B2  BI  = P5E_CPU0_PE0_RX_DN<14>
  B3  B3  BI  = GND
  B4  B4  BI  = P5E_CPU0_PE0_RX_DN<12>
  B5  B5  BI  = GND
  B6  B6  BI  = P5E_CPU0_PE0_RX_DN<10>
  B7  B7  BI  = GND
  B8  B8  BI  = P5E_CPU0_PE0_RX_DN<8>
  C1  C1  BI  = P5E_CPU0_PE0_RX_DN<15>
  C2  C2  BI  = P5E_CPU0_PE0_RX_DP<14>
  C3  C3  BI  = P5E_CPU0_PE0_RX_DN<13>
  C4  C4  BI  = P5E_CPU0_PE0_RX_DP<12>
  C5  C5  BI  = P5E_CPU0_PE0_RX_DP<11>
  C6  C6  BI  = P5E_CPU0_PE0_RX_DP<10>
  C7  C7  BI  = P5E_CPU0_PE0_RX_DN<9>
  C8  C8  BI  = P5E_CPU0_PE0_RX_DP<8>
  D1  D1  BI  = P5E_CPU0_PE0_RX_DP<15>
  D2  D2  BI  = GND
  D3  D3  BI  = P5E_CPU0_PE0_RX_DP<13>
  D4  D4  BI  = GND
  D5  D5  BI  = P5E_CPU0_PE0_RX_DN<11>
  D6  D6  BI  = GND
  D7  D7  BI  = P5E_CPU0_PE0_RX_DP<9>
  D8  D8  BI  = GND
  E1  E1  BI  = GND
  E2  E2  BI  = P5E_CPU0_PE4_RX_DP<1>
  E3  E3  BI  = GND
  E4  E4  BI  = P5E_CPU0_PE4_RX_DP<3>
  E5  E5  BI  = GND
  E6  E6  BI  = P5E_CPU0_PE4_RX_DP<5>
  E7  E7  BI  = GND
  E8  E8  BI  = P5E_CPU0_PE4_RX_DP<7>
  F1  F1  BI  = P5E_CPU0_PE4_RX_DN<0>
  F2  F2  BI  = P5E_CPU0_PE4_RX_DN<1>
  F3  F3  BI  = P5E_CPU0_PE4_RX_DN<2>
  F4  F4  BI  = P5E_CPU0_PE4_RX_DN<3>
  F5  F5  BI  = P5E_CPU0_PE4_RX_DN<4>
  F6  F6  BI  = P5E_CPU0_PE4_RX_DN<5>
  F7  F7  BI  = P5E_CPU0_PE4_RX_DN<6>
  F8  F8  BI  = P5E_CPU0_PE4_RX_DN<7>
  G1  G1  BI  = P5E_CPU0_PE4_RX_DP<0>
  G2  G2  BI  = GND
  G3  G3  BI  = P5E_CPU0_PE4_RX_DP<2>
  G4  G4  BI  = GND
  G5  G5  BI  = P5E_CPU0_PE4_RX_DP<4>
  G6  G6  BI  = GND
  G7  G7  BI  = P5E_CPU0_PE4_RX_DP<6>
  G8  G8  BI  = GND
  H1  H1  BI  = GND
  H2  H2  BI  = P5E_CPU0_PE0_TX_C_DN<14>
  H3  H3  BI  = GND
  H4  H4  BI  = P5E_CPU0_PE0_TX_C_DN<12>
  H5  H5  BI  = GND
  H6  H6  BI  = P5E_CPU0_PE0_TX_C_DN<10>
  H7  H7  BI  = GND
  H8  H8  BI  = P5E_CPU0_PE0_TX_C_DN<8>
  I1  I1  BI  = P5E_CPU0_PE0_TX_C_DN<15>
  I2  I2  BI  = P5E_CPU0_PE0_TX_C_DP<14>
  I3  I3  BI  = P5E_CPU0_PE0_TX_C_DN<13>
  I4  I4  BI  = P5E_CPU0_PE0_TX_C_DP<12>
  I5  I5  BI  = P5E_CPU0_PE0_TX_C_DN<11>
  I6  I6  BI  = P5E_CPU0_PE0_TX_C_DP<10>
  I7  I7  BI  = P5E_CPU0_PE0_TX_C_DN<9>
  I8  I8  BI  = P5E_CPU0_PE0_TX_C_DP<8>
  J1  J1  BI  = P5E_CPU0_PE0_TX_C_DP<15>
  J2  J2  BI  = GND
  J3  J3  BI  = P5E_CPU0_PE0_TX_C_DP<13>
  J4  J4  BI  = GND
  J5  J5  BI  = P5E_CPU0_PE0_TX_C_DP<11>
  J6  J6  BI  = GND
  J7  J7  BI  = P5E_CPU0_PE0_TX_C_DP<9>
  J8  J8  BI  = GND
  K1  K1  BI  = GND
  K2  K2  BI  = P5E_CPU0_PE4_TX_C_DP<1>
  K3  K3  BI  = GND
  K4  K4  BI  = P5E_CPU0_PE4_TX_C_DN<3>
  K5  K5  BI  = GND
  K6  K6  BI  = P5E_CPU0_PE4_TX_C_DN<5>
  K7  K7  BI  = GND
  K8  K8  BI  = P5E_CPU0_PE4_TX_C_DN<7>
  L1  L1  BI  = P5E_CPU0_PE4_TX_C_DN<0>
  L2  L2  BI  = P5E_CPU0_PE4_TX_C_DN<1>
  L3  L3  BI  = P5E_CPU0_PE4_TX_C_DN<2>
  L4  L4  BI  = P5E_CPU0_PE4_TX_C_DP<3>
  L5  L5  BI  = P5E_CPU0_PE4_TX_C_DN<4>
  L6  L6  BI  = P5E_CPU0_PE4_TX_C_DP<5>
  L7  L7  BI  = P5E_CPU0_PE4_TX_C_DN<6>
  L8  L8  BI  = P5E_CPU0_PE4_TX_C_DP<7>
  M1  M1  BI  = P5E_CPU0_PE4_TX_C_DP<0>
  M2  M2  BI  = GND
  M3  M3  BI  = P5E_CPU0_PE4_TX_C_DP<2>
  M4  M4  BI  = GND
  M5  M5  BI  = P5E_CPU0_PE4_TX_C_DP<4>
  M6  M6  BI  = GND
  M7  M7  BI  = P5E_CPU0_PE4_TX_C_DP<6>
  M8  M8  BI  = GND
  N1  N1  BI  = GND
  N2  N2  BI  = NC_J108_N2
  N3  N3  BI  = GND
  N4  N4  BI  = NC_J108_N4
  N5  N5  BI  = GND
  N6  N6  BI  = NC_J108_N6
  N7  N7  BI  = GND
  N8  N8  BI  = PRSNT_CABLE_GPU_A3_N
